# S9S_MB_2U (Grand Teton) — schematic netlist excerpt (pin names and nets, part order shuffled) for the footprints in the layout excerpt that follows; sources: Cadence DE-HDL packaged netlist, KiCad conversion of 03242023_DA0F0TMBIJ0_F0T_Motherboard_J_brd_V01_OCP.brd

R4471  Q_RES  0 5% EMPTY  pkg 0402LF  page 196 : A = USB2_PCH_0_R_DP ; B = USB2_0_DP
PD108  SCHOTTKY_AC  B340A-13-F IC  pkg D2010XF  page 162 : A = GND ; C = P12V_OCP_V3_2

(kicad_pcb
	(version 20260206)
	(generator "pcbnew")
	(generator_version "10.0")
	(general
		(thickness 1.6)
		(legacy_teardrops no)
	)
	(paper "A4")
	(title_block
		(title "03242023_DA0F0TMBIJ0_F0T_Motherboard_J_brd_V01_OCP.brd")
		(comment 1 "Grand Teton / footprints 1796-1797 of 6105")
	)
	(layers
		(0 "F.Cu" signal "TOP")
		(4 "In1.Cu" signal "GND")
		(6 "In2.Cu" signal "IN1")
		(8 "In3.Cu" signal "GND1")
		(10 "In4.Cu" signal "IN2")
		(12 "In5.Cu" signal "GND2")
		(14 "In6.Cu" signal "IN3")
		(16 "In7.Cu" signal "GND3")
		(18 "In8.Cu" signal "VCC")
		(20 "In9.Cu" signal "VCC1")
		(22 "In10.Cu" signal "GND4")
		(24 "In11.Cu" signal "IN4")
		(26 "In12.Cu" signal "GND5")
		(28 "In13.Cu" signal "IN5")
		(30 "In14.Cu" signal "GND6")
		(32 "In15.Cu" signal "IN6")
		(34 "In16.Cu" signal "GND7")
		(2 "B.Cu" signal "BOTTOM")
		(9 "F.Adhes" user "F.Adhesive")
		(11 "B.Adhes" user "B.Adhesive")
		(13 "F.Paste" user "Package Geometry/Pastemask Top")
		(15 "B.Paste" user "Package Geometry/Pastemask Bottom")
		(5 "F.SilkS" user "Ref Des/Silkscreen Top")
		(7 "B.SilkS" user "Ref Des/Silkscreen Bottom")
		(1 "F.Mask" user "Board Geometry/Soldermask Top")
		(3 "B.Mask" user "Board Geometry/Soldermask Bottom")
		(17 "Dwgs.User" user "User.Drawings")
		(19 "Cmts.User" user "User.Comments")
		(21 "Eco1.User" user "User.Eco1")
		(23 "Eco2.User" user "User.Eco2")
		(25 "Edge.Cuts" user "Board Geometry/Outline")
		(27 "Margin" user)
		(31 "F.CrtYd" user "Package Geometry/Place Bound Top")
		(29 "B.CrtYd" user "Package Geometry/Place Bound Bottom")
		(35 "F.Fab" user "Ref Des/Assembly Top")
		(33 "B.Fab" user "Ref Des/Assembly Bottom")
	)
	(footprint ""
		(layer "F.Cu")
		(at 158.901384 -43.832526 90)
		(property "Reference" "R4471"
			(at 0 0 90)
			(layer "F.SilkS")
			(hide yes)
			(effects
				(font
					(size 1.27 1.27)
				)
			)
		)
		(property "Value" ""
			(at 0 0 90)
			(layer "F.Fab")
			(effects
				(font
					(size 1.27 1.27)
				)
			)
		)
		(duplicate_pad_numbers_are_jumpers no)
		(fp_line
			(start 0.7874 -0.4064)
			(end 0.7874 0.4064)
			(stroke
				(width 0.1524)
				(type default)
			)
			(layer "F.SilkS")
		)
		(fp_line
			(start -0.7874 -0.4064)
			(end 0.7874 -0.4064)
			(stroke
				(width 0.1524)
				(type default)
			)
			(layer "F.SilkS")
		)
		(fp_line
			(start -0.12065 -0.305054)
			(end -0.12065 -0.2794)
			(stroke
				(width 0.1)
				(type default)
			)
			(layer "F.Fab")
		)
		(fp_line
			(start -0.67945 -0.305054)
			(end -0.12065 -0.305054)
			(stroke
				(width 0.1)
				(type default)
			)
			(layer "F.Fab")
		)
		(fp_line
			(start 0.67945 -0.3048)
			(end 0.67945 0.3048)
			(stroke
				(width 0.1)
				(type default)
			)
			(layer "F.Fab")
		)
		(fp_line
			(start 0.12065 -0.3048)
			(end 0.67945 -0.3048)
			(stroke
				(width 0.1)
				(type default)
			)
			(layer "F.Fab")
		)
		(fp_line
			(start 0.12065 -0.2794)
			(end 0.12065 -0.3048)
			(stroke
				(width 0.1)
				(type default)
			)
			(layer "F.Fab")
		)
		(fp_line
			(start -0.12065 -0.2794)
			(end 0.12065 -0.2794)
			(stroke
				(width 0.1)
				(type default)
			)
			(layer "F.Fab")
		)
		(fp_line
			(start 0.120396 0.2794)
			(end -0.12065 0.2794)
			(stroke
				(width 0.1)
				(type default)
			)
			(layer "F.Fab")
		)
		(fp_line
			(start -0.12065 0.2794)
			(end -0.12065 0.3048)
			(stroke
				(width 0.1)
				(type default)
			)
			(layer "F.Fab")
		)
		(fp_line
			(start 0.67945 0.3048)
			(end 0.120396 0.3048)
			(stroke
				(width 0.1)
				(type default)
			)
			(layer "F.Fab")
		)
		(fp_line
			(start 0.120396 0.3048)
			(end 0.120396 0.2794)
			(stroke
				(width 0.1)
				(type default)
			)
			(layer "F.Fab")
		)
		(fp_line
			(start -0.12065 0.3048)
			(end -0.67945 0.3048)
			(stroke
				(width 0.1)
				(type default)
			)
			(layer "F.Fab")
		)
		(fp_line
			(start -0.67945 0.3048)
			(end -0.67945 -0.305054)
			(stroke
				(width 0.1)
				(type default)
			)
			(layer "F.Fab")
		)
		(pad "1" smd rect
			(at -0.40005 0 270)
			(size 0.4572 0.508)
			(layers "F.Cu" "F.Mask" "F.Paste")
			(net "USB2_PCH_0_R_DP")
		)
		(pad "2" smd rect
			(at 0.40005 0 270)
			(size 0.4572 0.508)
			(layers "F.Cu" "F.Mask" "F.Paste")
			(net "USB2_0_DP")
		)
	)
	(footprint ""
		(layer "F.Cu")
		(at 81.424018 -15.177262 180)
		(property "Reference" "PD108"
			(at -4.814824 -0.9271 0)
			(unlocked yes)
			(layer "F.SilkS")
			(effects
				(font
					(size 0.7874 0.5842)
					(thickness 0.1524)
				)
				(justify left)
			)
		)
		(property "Value" ""
			(at 0 0 180)
			(layer "F.Fab")
			(effects
				(font
					(size 1.27 1.27)
				)
			)
		)
		(duplicate_pad_numbers_are_jumpers no)
		(fp_line
			(start 4.107942 1.459992)
			(end -3.400044 1.459992)
			(stroke
				(width 0.1524)
				(type default)
			)
			(layer "F.SilkS")
		)
		(fp_line
			(start 4.107942 -1.459992)
			(end 4.107942 1.459992)
			(stroke
				(width 0.1524)
				(type default)
			)
			(layer "F.SilkS")
		)
		(fp_line
			(start -3.400044 1.459992)
			(end -3.400044 -1.459992)
			(stroke
				(width 0.1524)
				(type default)
			)
			(layer "F.SilkS")
		)
		(fp_line
			(start -3.400044 -1.459992)
			(end 4.107942 -1.459992)
			(stroke
				(width 0.1524)
				(type default)
			)
			(layer "F.SilkS")
		)
		(fp_rect
			(start 4.107942 -1.459992)
			(end 3.308096 1.459992)
			(stroke
				(width 0)
				(type default)
			)
			(fill yes)
			(layer "F.SilkS")
		)
		(fp_line
			(start 2.29997 1.459992)
			(end -2.29997 1.459992)
			(stroke
				(width 0.1)
				(type default)
			)
			(layer "F.Fab")
		)
		(fp_line
			(start 2.29997 -1.459992)
			(end 2.29997 1.459992)
			(stroke
				(width 0.1)
				(type default)
			)
			(layer "F.Fab")
		)
		(fp_line
			(start -2.29997 1.459992)
			(end -2.29997 -1.459992)
			(stroke
				(width 0.1)
				(type default)
			)
			(layer "F.Fab")
		)
		(fp_line
			(start -2.29997 -1.459992)
			(end 2.29997 -1.459992)
			(stroke
				(width 0.1)
				(type default)
			)
			(layer "F.Fab")
		)
		(fp_text user "-"
			(at 5.4102 0.29845 0)
			(unlocked yes)
			(layer "F.SilkS")
			(effects
				(font
					(size 1.905 1.4224)
					(thickness 0.1524)
				)
				(justify left)
			)
		)
		(fp_text user "+"
			(at -4.7752 -0.12065 180)
			(unlocked yes)
			(layer "F.SilkS")
			(effects
				(font
					(size 1.905 1.4224)
					(thickness 0.1524)
				)
				(justify left)
			)
		)
		(fp_text user "-"
			(at 5.4102 0.29845 0)
			(unlocked yes)
			(layer "F.Fab")
			(effects
				(font
					(size 1.905 1.4224)
					(thickness 0.1524)
				)
				(justify left)
			)
		)
		(fp_text user "+"
			(at -4.7752 -0.12065 180)
			(unlocked yes)
			(layer "F.Fab")
			(effects
				(font
					(size 1.905 1.4224)
					(thickness 0.1524)
				)
				(justify left)
			)
		)
		(pad "A" smd rect
			(at -1.999996 0 270)
			(size 1.7018 2.5146)
			(layers "F.Cu" "F.Mask" "F.Paste")
			(net "GND")
		)
		(pad "C" smd rect
			(at 1.999996 0 270)
			(size 1.7018 2.5146)
			(layers "F.Cu" "F.Mask" "F.Paste")
			(net "P12V_OCP_V3_2")
		)
	)
)
